# T6G (Grand Teton) — schematic netlist excerpt (pin names and nets, part order shuffled) for the footprints in the layout excerpt that follows; sources: Cadence DE-HDL packaged netlist, KiCad conversion of 04192023_DAF0TMB3IC0_F0TG_MB_C_brd_V02_OCP.brd

R2268  Q_RES  0 5% CHIP  pkg 0402LF  page 250 : A = RST_SMB_SWITCH_N ; B = PU_RST_SMB_PCIE0_N
R9028  Q_RES  0 5% EMPTY  pkg 0402LF  page 85 : A = IRQ_HSC_FAULT_N ; B = IRQ_HSC_FAULT_BUF_N
C958  Q_CAP_DIFFBUS  DIFF BUS_0.22UF 6.3V 20% X6S  pkg C0201  page 63 : \1\ = P5E_CPU0_P1_TX_C_DN<3> ; \2\ = P5E_CPU0_P1_TX_DN<3>

(kicad_pcb
	(version 20260206)
	(generator "pcbnew")
	(generator_version "10.0")
	(general
		(thickness 1.6)
		(legacy_teardrops no)
	)
	(paper "A4")
	(title_block
		(title "04192023_DAF0TMB3IC0_F0TG_MB_C_brd_V02_OCP.brd")
		(comment 1 "Grand Teton / footprints 4875-4877 of 8354")
	)
	(layers
		(0 "F.Cu" signal "TOP")
		(4 "In1.Cu" signal "GND")
		(6 "In2.Cu" signal "IN1")
		(8 "In3.Cu" signal "GND1")
		(10 "In4.Cu" signal "IN2")
		(12 "In5.Cu" signal "GND2")
		(14 "In6.Cu" signal "IN3")
		(16 "In7.Cu" signal "GND3")
		(18 "In8.Cu" signal "VCC")
		(20 "In9.Cu" signal "VCC1")
		(22 "In10.Cu" signal "GND4")
		(24 "In11.Cu" signal "IN4")
		(26 "In12.Cu" signal "GND5")
		(28 "In13.Cu" signal "IN5")
		(30 "In14.Cu" signal "GND6")
		(32 "In15.Cu" signal "IN6")
		(34 "In16.Cu" signal "GND7")
		(2 "B.Cu" signal "BOTTOM")
		(9 "F.Adhes" user "F.Adhesive")
		(11 "B.Adhes" user "B.Adhesive")
		(13 "F.Paste" user "Package Geometry/Pastemask Top")
		(15 "B.Paste" user "Package Geometry/Pastemask Bottom")
		(5 "F.SilkS" user "Ref Des/Silkscreen Top")
		(7 "B.SilkS" user "Ref Des/Silkscreen Bottom")
		(1 "F.Mask" user "Board Geometry/Soldermask Top")
		(3 "B.Mask" user "Board Geometry/Soldermask Bottom")
		(17 "Dwgs.User" user "User.Drawings")
		(19 "Cmts.User" user "User.Comments")
		(21 "Eco1.User" user "User.Eco1")
		(23 "Eco2.User" user "User.Eco2")
		(25 "Edge.Cuts" user "Board Geometry/Outline")
		(27 "Margin" user)
		(31 "F.CrtYd" user "Package Geometry/Place Bound Top")
		(29 "B.CrtYd" user "Package Geometry/Place Bound Bottom")
		(35 "F.Fab" user "Ref Des/Assembly Top")
		(33 "B.Fab" user "Ref Des/Assembly Bottom")
	)
	(footprint ""
		(layer "F.Cu")
		(at 163.195 -106.807 90)
		(property "Reference" "R9028"
			(at 0 0 90)
			(layer "F.SilkS")
			(hide yes)
			(effects
				(font
					(size 1.27 1.27)
				)
			)
		)
		(property "Value" ""
			(at 0 0 90)
			(layer "F.Fab")
			(effects
				(font
					(size 1.27 1.27)
				)
			)
		)
		(duplicate_pad_numbers_are_jumpers no)
		(fp_line
			(start 0.7874 -0.4064)
			(end 0.7874 0.4064)
			(stroke
				(width 0.1524)
				(type default)
			)
			(layer "F.SilkS")
		)
		(fp_line
			(start -0.7874 -0.4064)
			(end 0.7874 -0.4064)
			(stroke
				(width 0.1524)
				(type default)
			)
			(layer "F.SilkS")
		)
		(fp_line
			(start 0.7874 0.4064)
			(end -0.7874 0.4064)
			(stroke
				(width 0.1524)
				(type default)
			)
			(layer "F.SilkS")
		)
		(fp_line
			(start -0.7874 0.4064)
			(end -0.7874 -0.4064)
			(stroke
				(width 0.1524)
				(type default)
			)
			(layer "F.SilkS")
		)
		(fp_line
			(start -0.12065 -0.305054)
			(end -0.12065 -0.2794)
			(stroke
				(width 0.1)
				(type default)
			)
			(layer "F.Fab")
		)
		(fp_line
			(start -0.67945 -0.305054)
			(end -0.12065 -0.305054)
			(stroke
				(width 0.1)
				(type default)
			)
			(layer "F.Fab")
		)
		(fp_line
			(start 0.67945 -0.3048)
			(end 0.67945 0.3048)
			(stroke
				(width 0.1)
				(type default)
			)
			(layer "F.Fab")
		)
		(fp_line
			(start 0.12065 -0.3048)
			(end 0.67945 -0.3048)
			(stroke
				(width 0.1)
				(type default)
			)
			(layer "F.Fab")
		)
		(fp_line
			(start 0.12065 -0.2794)
			(end 0.12065 -0.3048)
			(stroke
				(width 0.1)
				(type default)
			)
			(layer "F.Fab")
		)
		(fp_line
			(start -0.12065 -0.2794)
			(end 0.12065 -0.2794)
			(stroke
				(width 0.1)
				(type default)
			)
			(layer "F.Fab")
		)
		(fp_line
			(start 0.120396 0.2794)
			(end -0.12065 0.2794)
			(stroke
				(width 0.1)
				(type default)
			)
			(layer "F.Fab")
		)
		(fp_line
			(start -0.12065 0.2794)
			(end -0.12065 0.3048)
			(stroke
				(width 0.1)
				(type default)
			)
			(layer "F.Fab")
		)
		(fp_line
			(start 0.67945 0.3048)
			(end 0.120396 0.3048)
			(stroke
				(width 0.1)
				(type default)
			)
			(layer "F.Fab")
		)
		(fp_line
			(start 0.120396 0.3048)
			(end 0.120396 0.2794)
			(stroke
				(width 0.1)
				(type default)
			)
			(layer "F.Fab")
		)
		(fp_line
			(start -0.12065 0.3048)
			(end -0.67945 0.3048)
			(stroke
				(width 0.1)
				(type default)
			)
			(layer "F.Fab")
		)
		(fp_line
			(start -0.67945 0.3048)
			(end -0.67945 -0.305054)
			(stroke
				(width 0.1)
				(type default)
			)
			(layer "F.Fab")
		)
		(pad "1" smd circle
			(at -0.40005 0 90)
			(size 0 0)
			(layers "F.Cu" "F.Mask" "F.Paste")
			(net "IRQ_HSC_FAULT_N")
		)
		(pad "2" smd circle
			(at 0.40005 0 90)
			(size 0 0)
			(layers "F.Cu" "F.Mask" "F.Paste")
			(net "IRQ_HSC_FAULT_BUF_N")
		)
	)
	(footprint ""
		(layer "F.Cu")
		(at 279.513792 -121.75617)
		(property "Reference" "R2268"
			(at 0 0 0)
			(layer "F.SilkS")
			(hide yes)
			(effects
				(font
					(size 1.27 1.27)
				)
			)
		)
		(property "Value" ""
			(at 0 0 0)
			(layer "F.Fab")
			(effects
				(font
					(size 1.27 1.27)
				)
			)
		)
		(duplicate_pad_numbers_are_jumpers no)
		(fp_line
			(start -0.7874 -0.4064)
			(end 0.7874 -0.4064)
			(stroke
				(width 0.1524)
				(type default)
			)
			(layer "F.SilkS")
		)
		(fp_line
			(start -0.7874 0.4064)
			(end -0.7874 -0.4064)
			(stroke
				(width 0.1524)
				(type default)
			)
			(layer "F.SilkS")
		)
		(fp_line
			(start 0.7874 -0.4064)
			(end 0.7874 0.4064)
			(stroke
				(width 0.1524)
				(type default)
			)
			(layer "F.SilkS")
		)
		(fp_line
			(start 0.7874 0.4064)
			(end -0.7874 0.4064)
			(stroke
				(width 0.1524)
				(type default)
			)
			(layer "F.SilkS")
		)
		(fp_line
			(start -0.67945 -0.305054)
			(end -0.12065 -0.305054)
			(stroke
				(width 0.1)
				(type default)
			)
			(layer "F.Fab")
		)
		(fp_line
			(start -0.67945 0.3048)
			(end -0.67945 -0.305054)
			(stroke
				(width 0.1)
				(type default)
			)
			(layer "F.Fab")
		)
		(fp_line
			(start -0.12065 -0.305054)
			(end -0.12065 -0.2794)
			(stroke
				(width 0.1)
				(type default)
			)
			(layer "F.Fab")
		)
		(fp_line
			(start -0.12065 -0.2794)
			(end 0.12065 -0.2794)
			(stroke
				(width 0.1)
				(type default)
			)
			(layer "F.Fab")
		)
		(fp_line
			(start -0.12065 0.2794)
			(end -0.12065 0.3048)
			(stroke
				(width 0.1)
				(type default)
			)
			(layer "F.Fab")
		)
		(fp_line
			(start -0.12065 0.3048)
			(end -0.67945 0.3048)
			(stroke
				(width 0.1)
				(type default)
			)
			(layer "F.Fab")
		)
		(fp_line
			(start 0.120396 0.2794)
			(end -0.12065 0.2794)
			(stroke
				(width 0.1)
				(type default)
			)
			(layer "F.Fab")
		)
		(fp_line
			(start 0.120396 0.3048)
			(end 0.120396 0.2794)
			(stroke
				(width 0.1)
				(type default)
			)
			(layer "F.Fab")
		)
		(fp_line
			(start 0.12065 -0.3048)
			(end 0.67945 -0.3048)
			(stroke
				(width 0.1)
				(type default)
			)
			(layer "F.Fab")
		)
		(fp_line
			(start 0.12065 -0.2794)
			(end 0.12065 -0.3048)
			(stroke
				(width 0.1)
				(type default)
			)
			(layer "F.Fab")
		)
		(fp_line
			(start 0.67945 -0.3048)
			(end 0.67945 0.3048)
			(stroke
				(width 0.1)
				(type default)
			)
			(layer "F.Fab")
		)
		(fp_line
			(start 0.67945 0.3048)
			(end 0.120396 0.3048)
			(stroke
				(width 0.1)
				(type default)
			)
			(layer "F.Fab")
		)
		(pad "1" smd circle
			(at -0.40005 0)
			(size 0 0)
			(layers "F.Cu" "F.Mask" "F.Paste")
			(net "RST_SMB_SWITCH_N")
		)
		(pad "2" smd circle
			(at 0.40005 0)
			(size 0 0)
			(layers "F.Cu" "F.Mask" "F.Paste")
			(net "PU_RST_SMB_PCIE0_N")
		)
	)
	(footprint ""
		(layer "F.Cu")
		(at 334.133444 -378.95403 -90)
		(property "Reference" "C958"
			(at 0 0 270)
			(layer "F.SilkS")
			(hide yes)
			(effects
				(font
					(size 1.27 1.27)
				)
			)
		)
		(property "Value" ""
			(at 0 0 270)
			(layer "F.Fab")
			(effects
				(font
					(size 1.27 1.27)
				)
			)
		)
		(duplicate_pad_numbers_are_jumpers no)
		(fp_line
			(start -0.299974 0.150114)
			(end -0.299974 -0.150114)
			(stroke
				(width 0.1)
				(type default)
			)
			(layer "F.Fab")
		)
		(fp_line
			(start 0.299974 0.150114)
			(end -0.299974 0.150114)
			(stroke
				(width 0.1)
				(type default)
			)
			(layer "F.Fab")
		)
		(fp_line
			(start -0.299974 -0.150114)
			(end 0.299974 -0.150114)
			(stroke
				(width 0.1)
				(type default)
			)
			(layer "F.Fab")
		)
		(fp_line
			(start 0.299974 -0.150114)
			(end 0.299974 0.150114)
			(stroke
				(width 0.1)
				(type default)
			)
			(layer "F.Fab")
		)
		(pad "1" smd rect
			(at -0.2667 0 270)
			(size 0.3048 0.381)
			(layers "F.Cu" "F.Mask" "F.Paste")
			(net "P5E_CPU0_P1_TX_C_DN<3>")
		)
		(pad "2" smd rect
			(at 0.2667 0 270)
			(size 0.3048 0.381)
			(layers "F.Cu" "F.Mask" "F.Paste")
			(net "P5E_CPU0_P1_TX_DN<3>")
		)
	)
)
